# T6G (Grand Teton) — schematic netlist excerpt (pin names and nets, part order shuffled) for the footprints in the layout excerpt that follows; sources: Cadence DE-HDL packaged netlist, KiCad conversion of 04192023_DAF0TMB3IC0_F0TG_MB_C_brd_V02_OCP.brd

R8026  Q_RES  560 1% CHIP  pkg 0402LF  page 256 : A = LED_P12V_PSU_R2 ; B = LED_P12V_PSU_R3
C2460  Q_CAP  22UF 4V 20% X6S  pkg C0402  page 74 : A = PVDDCR_SOC_P1 ; B = GND
R1429  Q_RES  1K 1% CHIP  pkg 0201LF  page 353 : A = JTAG_TRST_RT_CPU1_P3_N ; B = GND

(kicad_pcb
	(version 20260206)
	(generator "pcbnew")
	(generator_version "10.0")
	(general
		(thickness 1.6)
		(legacy_teardrops no)
	)
	(paper "A4")
	(title_block
		(title "04192023_DAF0TMB3IC0_F0TG_MB_C_brd_V02_OCP.brd")
		(comment 1 "Grand Teton / footprints 183-185 of 8354")
	)
	(layers
		(0 "F.Cu" signal "TOP")
		(4 "In1.Cu" signal "GND")
		(6 "In2.Cu" signal "IN1")
		(8 "In3.Cu" signal "GND1")
		(10 "In4.Cu" signal "IN2")
		(12 "In5.Cu" signal "GND2")
		(14 "In6.Cu" signal "IN3")
		(16 "In7.Cu" signal "GND3")
		(18 "In8.Cu" signal "VCC")
		(20 "In9.Cu" signal "VCC1")
		(22 "In10.Cu" signal "GND4")
		(24 "In11.Cu" signal "IN4")
		(26 "In12.Cu" signal "GND5")
		(28 "In13.Cu" signal "IN5")
		(30 "In14.Cu" signal "GND6")
		(32 "In15.Cu" signal "IN6")
		(34 "In16.Cu" signal "GND7")
		(2 "B.Cu" signal "BOTTOM")
		(9 "F.Adhes" user "F.Adhesive")
		(11 "B.Adhes" user "B.Adhesive")
		(13 "F.Paste" user "Package Geometry/Pastemask Top")
		(15 "B.Paste" user "Package Geometry/Pastemask Bottom")
		(5 "F.SilkS" user "Ref Des/Silkscreen Top")
		(7 "B.SilkS" user "Ref Des/Silkscreen Bottom")
		(1 "F.Mask" user "Board Geometry/Soldermask Top")
		(3 "B.Mask" user "Board Geometry/Soldermask Bottom")
		(17 "Dwgs.User" user "User.Drawings")
		(19 "Cmts.User" user "User.Comments")
		(21 "Eco1.User" user "User.Eco1")
		(23 "Eco2.User" user "User.Eco2")
		(25 "Edge.Cuts" user "Board Geometry/Outline")
		(27 "Margin" user)
		(31 "F.CrtYd" user "Package Geometry/Place Bound Top")
		(29 "B.CrtYd" user "Package Geometry/Place Bound Bottom")
		(35 "F.Fab" user "Ref Des/Assembly Top")
		(33 "B.Fab" user "Ref Des/Assembly Bottom")
	)
	(footprint ""
		(layer "F.Cu")
		(at 136.803638 -389.816086)
		(property "Reference" "R1429"
			(at 0 0 0)
			(layer "F.SilkS")
			(hide yes)
			(effects
				(font
					(size 1.27 1.27)
				)
			)
		)
		(property "Value" ""
			(at 0 0 0)
			(layer "F.Fab")
			(effects
				(font
					(size 1.27 1.27)
				)
			)
		)
		(duplicate_pad_numbers_are_jumpers no)
		(fp_line
			(start -0.32512 -0.175006)
			(end 0.32512 -0.175006)
			(stroke
				(width 0.1)
				(type default)
			)
			(layer "F.Fab")
		)
		(fp_line
			(start -0.32512 0.175006)
			(end -0.32512 -0.175006)
			(stroke
				(width 0.1)
				(type default)
			)
			(layer "F.Fab")
		)
		(fp_line
			(start 0.32512 -0.175006)
			(end 0.32512 0.175006)
			(stroke
				(width 0.1)
				(type default)
			)
			(layer "F.Fab")
		)
		(fp_line
			(start 0.32512 0.175006)
			(end -0.32512 0.175006)
			(stroke
				(width 0.1)
				(type default)
			)
			(layer "F.Fab")
		)
		(pad "1" smd rect
			(at -0.2667 0)
			(size 0.3048 0.381)
			(layers "F.Cu" "F.Mask" "F.Paste")
			(net "JTAG_TRST_RT_CPU1_P3_N")
		)
		(pad "2" smd rect
			(at 0.2667 0 180)
			(size 0.3048 0.381)
			(layers "F.Cu" "F.Mask" "F.Paste")
			(net "GND")
		)
	)
	(footprint ""
		(layer "F.Cu")
		(at 111.476028 -256.012442 90)
		(property "Reference" "C2460"
			(at 0 0 90)
			(layer "F.SilkS")
			(hide yes)
			(effects
				(font
					(size 1.27 1.27)
				)
			)
		)
		(property "Value" ""
			(at 0 0 90)
			(layer "F.Fab")
			(effects
				(font
					(size 1.27 1.27)
				)
			)
		)
		(duplicate_pad_numbers_are_jumpers no)
		(fp_line
			(start 0.7874 -0.4064)
			(end 0.7874 0.4064)
			(stroke
				(width 0.1524)
				(type default)
			)
			(layer "F.SilkS")
		)
		(fp_line
			(start -0.7874 -0.4064)
			(end 0.7874 -0.4064)
			(stroke
				(width 0.1524)
				(type default)
			)
			(layer "F.SilkS")
		)
		(fp_line
			(start 0.7874 0.4064)
			(end -0.7874 0.4064)
			(stroke
				(width 0.1524)
				(type default)
			)
			(layer "F.SilkS")
		)
		(fp_line
			(start -0.7874 0.4064)
			(end -0.7874 -0.4064)
			(stroke
				(width 0.1524)
				(type default)
			)
			(layer "F.SilkS")
		)
		(fp_line
			(start -0.12065 -0.305054)
			(end -0.12065 -0.2794)
			(stroke
				(width 0.1)
				(type default)
			)
			(layer "F.Fab")
		)
		(fp_line
			(start -0.67945 -0.305054)
			(end -0.12065 -0.305054)
			(stroke
				(width 0.1)
				(type default)
			)
			(layer "F.Fab")
		)
		(fp_line
			(start 0.67945 -0.3048)
			(end 0.67945 0.3048)
			(stroke
				(width 0.1)
				(type default)
			)
			(layer "F.Fab")
		)
		(fp_line
			(start 0.12065 -0.3048)
			(end 0.67945 -0.3048)
			(stroke
				(width 0.1)
				(type default)
			)
			(layer "F.Fab")
		)
		(fp_line
			(start 0.12065 -0.2794)
			(end 0.12065 -0.3048)
			(stroke
				(width 0.1)
				(type default)
			)
			(layer "F.Fab")
		)
		(fp_line
			(start -0.12065 -0.2794)
			(end 0.12065 -0.2794)
			(stroke
				(width 0.1)
				(type default)
			)
			(layer "F.Fab")
		)
		(fp_line
			(start 0.120396 0.2794)
			(end -0.12065 0.2794)
			(stroke
				(width 0.1)
				(type default)
			)
			(layer "F.Fab")
		)
		(fp_line
			(start -0.12065 0.2794)
			(end -0.12065 0.3048)
			(stroke
				(width 0.1)
				(type default)
			)
			(layer "F.Fab")
		)
		(fp_line
			(start 0.67945 0.3048)
			(end 0.120396 0.3048)
			(stroke
				(width 0.1)
				(type default)
			)
			(layer "F.Fab")
		)
		(fp_line
			(start 0.120396 0.3048)
			(end 0.120396 0.2794)
			(stroke
				(width 0.1)
				(type default)
			)
			(layer "F.Fab")
		)
		(fp_line
			(start -0.12065 0.3048)
			(end -0.67945 0.3048)
			(stroke
				(width 0.1)
				(type default)
			)
			(layer "F.Fab")
		)
		(fp_line
			(start -0.67945 0.3048)
			(end -0.67945 -0.305054)
			(stroke
				(width 0.1)
				(type default)
			)
			(layer "F.Fab")
		)
		(pad "1" smd circle
			(at -0.40005 0 90)
			(size 0 0)
			(layers "F.Cu" "F.Mask" "F.Paste")
			(net "PVDDCR_SOC_P1")
		)
		(pad "2" smd circle
			(at 0.40005 0 90)
			(size 0 0)
			(layers "F.Cu" "F.Mask" "F.Paste")
			(net "GND")
		)
	)
	(footprint ""
		(layer "F.Cu")
		(at 38.180772 -53.837332 -90)
		(property "Reference" "R8026"
			(at 0 0 270)
			(layer "F.SilkS")
			(hide yes)
			(effects
				(font
					(size 1.27 1.27)
				)
			)
		)
		(property "Value" ""
			(at 0 0 270)
			(layer "F.Fab")
			(effects
				(font
					(size 1.27 1.27)
				)
			)
		)
		(duplicate_pad_numbers_are_jumpers no)
		(fp_line
			(start -0.7874 0.4064)
			(end -0.7874 -0.4064)
			(stroke
				(width 0.1524)
				(type default)
			)
			(layer "F.SilkS")
		)
		(fp_line
			(start 0.7874 0.4064)
			(end -0.7874 0.4064)
			(stroke
				(width 0.1524)
				(type default)
			)
			(layer "F.SilkS")
		)
		(fp_line
			(start -0.7874 -0.4064)
			(end 0.7874 -0.4064)
			(stroke
				(width 0.1524)
				(type default)
			)
			(layer "F.SilkS")
		)
		(fp_line
			(start 0.7874 -0.4064)
			(end 0.7874 0.4064)
			(stroke
				(width 0.1524)
				(type default)
			)
			(layer "F.SilkS")
		)
		(fp_line
			(start -0.67945 0.3048)
			(end -0.67945 -0.305054)
			(stroke
				(width 0.1)
				(type default)
			)
			(layer "F.Fab")
		)
		(fp_line
			(start -0.12065 0.3048)
			(end -0.67945 0.3048)
			(stroke
				(width 0.1)
				(type default)
			)
			(layer "F.Fab")
		)
		(fp_line
			(start 0.120396 0.3048)
			(end 0.120396 0.2794)
			(stroke
				(width 0.1)
				(type default)
			)
			(layer "F.Fab")
		)
		(fp_line
			(start 0.67945 0.3048)
			(end 0.120396 0.3048)
			(stroke
				(width 0.1)
				(type default)
			)
			(layer "F.Fab")
		)
		(fp_line
			(start -0.12065 0.2794)
			(end -0.12065 0.3048)
			(stroke
				(width 0.1)
				(type default)
			)
			(layer "F.Fab")
		)
		(fp_line
			(start 0.120396 0.2794)
			(end -0.12065 0.2794)
			(stroke
				(width 0.1)
				(type default)
			)
			(layer "F.Fab")
		)
		(fp_line
			(start -0.12065 -0.2794)
			(end 0.12065 -0.2794)
			(stroke
				(width 0.1)
				(type default)
			)
			(layer "F.Fab")
		)
		(fp_line
			(start 0.12065 -0.2794)
			(end 0.12065 -0.3048)
			(stroke
				(width 0.1)
				(type default)
			)
			(layer "F.Fab")
		)
		(fp_line
			(start 0.12065 -0.3048)
			(end 0.67945 -0.3048)
			(stroke
				(width 0.1)
				(type default)
			)
			(layer "F.Fab")
		)
		(fp_line
			(start 0.67945 -0.3048)
			(end 0.67945 0.3048)
			(stroke
				(width 0.1)
				(type default)
			)
			(layer "F.Fab")
		)
		(fp_line
			(start -0.67945 -0.305054)
			(end -0.12065 -0.305054)
			(stroke
				(width 0.1)
				(type default)
			)
			(layer "F.Fab")
		)
		(fp_line
			(start -0.12065 -0.305054)
			(end -0.12065 -0.2794)
			(stroke
				(width 0.1)
				(type default)
			)
			(layer "F.Fab")
		)
		(pad "1" smd circle
			(at -0.40005 0 270)
			(size 0 0)
			(layers "F.Cu" "F.Mask" "F.Paste")
			(net "LED_P12V_PSU_R2")
		)
		(pad "2" smd circle
			(at 0.40005 0 270)
			(size 0 0)
			(layers "F.Cu" "F.Mask" "F.Paste")
			(net "LED_P12V_PSU_R3")
		)
	)
)
